(kicad_pcb
	(version 20260206)
	(generator "pcbnew")
	(generator_version "10.0")
	(general
		(thickness 1.6)
		(legacy_teardrops no)
	)
	(paper "A4")
	(title_block
		(title "Wiwynn_Tioga_Pass_MB.brd")
		(comment 1 "Tioga Pass / footprints 1964-1970 of 4770")
	)
	(layers
		(0 "F.Cu" signal "TOP")
		(4 "In1.Cu" signal "L2GND")
		(6 "In2.Cu" signal "L3")
		(8 "In3.Cu" signal "L4GND")
		(10 "In4.Cu" signal "L5")
		(12 "In5.Cu" signal "L6GND")
		(14 "In6.Cu" signal "L7VCC")
		(16 "In7.Cu" signal "L8VCC")
		(18 "In8.Cu" signal "L9GND")
		(20 "In9.Cu" signal "L10")
		(22 "In10.Cu" signal "L11GND")
		(24 "In11.Cu" signal "L12")
		(26 "In12.Cu" signal "L13GND")
		(2 "B.Cu" signal "BOTTOM")
		(9 "F.Adhes" user "F.Adhesive")
		(11 "B.Adhes" user "B.Adhesive")
		(13 "F.Paste" user "Package Geometry/Pastemask Top")
		(15 "B.Paste" user "Package Geometry/Pastemask Bottom")
		(5 "F.SilkS" user "Ref Des/Silkscreen Top")
		(7 "B.SilkS" user "Ref Des/Silkscreen Bottom")
		(1 "F.Mask" user "Board Geometry/Soldermask Top")
		(3 "B.Mask" user "Board Geometry/Soldermask Bottom")
		(17 "Dwgs.User" user "User.Drawings")
		(19 "Cmts.User" user "User.Comments")
		(21 "Eco1.User" user "User.Eco1")
		(23 "Eco2.User" user "User.Eco2")
		(25 "Edge.Cuts" user "Board Geometry/Outline")
		(27 "Margin" user)
		(31 "F.CrtYd" user "Package Geometry/Place Bound Top")
		(29 "B.CrtYd" user "Package Geometry/Place Bound Bottom")
		(35 "F.Fab" user "Ref Des/Assembly Top")
		(33 "B.Fab" user "Ref Des/Assembly Bottom")
	)
	(footprint ""
		(layer "F.Cu")
		(at 343.492328 -156.591 180)
		(property "Reference" "CT44"
			(at -0.8382 -0.67818 180)
			(unlocked yes)
			(layer "F.SilkS")
			(effects
				(font
					(size 0.4064 0.254)
					(thickness 0.1524)
				)
				(justify left)
			)
		)
		(property "Value" ""
			(at 0 0 180)
			(layer "F.Fab")
			(effects
				(font
					(size 1.27 1.27)
				)
			)
		)
		(duplicate_pad_numbers_are_jumpers no)
		(fp_poly
			(pts
				(xy 0.3048 -0.1016) (xy 0.3048 0.9906) (xy -0.3048 0.9906) (xy -0.3048 -0.1016)
			)
			(stroke
				(width 0)
				(type default)
			)
			(fill no)
			(layer "F.CrtYd")
		)
		(fp_line
			(start 0.3048 0.9906)
			(end 0.3048 -0.1016)
			(stroke
				(width 0.1)
				(type default)
			)
			(layer "F.Fab")
		)
		(fp_line
			(start 0.3048 -0.1016)
			(end -0.3048 -0.1016)
			(stroke
				(width 0.1)
				(type default)
			)
			(layer "F.Fab")
		)
		(fp_line
			(start -0.3048 0.9906)
			(end 0.3048 0.9906)
			(stroke
				(width 0.1)
				(type default)
			)
			(layer "F.Fab")
		)
		(fp_line
			(start -0.3048 -0.1016)
			(end -0.3048 0.9906)
			(stroke
				(width 0.1)
				(type default)
			)
			(layer "F.Fab")
		)
		(pad "1" smd rect
			(at 0 0 180)
			(size 0.508 0.508)
			(layers "F.Cu" "F.Mask" "F.Paste")
			(net "VR_PVDDQ_DEF_PH1_SW")
		)
		(pad "2" smd rect
			(at 0 0.889 180)
			(size 0.508 0.508)
			(layers "F.Cu" "F.Mask" "F.Paste")
			(net "VR_PVDDQ_DEF_PH1_SW_RC")
		)
		(zone
			(layer "F.Cu")
			(hatch none 0.5)
			(connect_pads
				(clearance 0)
			)
			(min_thickness 0.25)
			(keepout
				(tracks not_allowed)
				(vias allowed)
				(pads allowed)
				(copperpour not_allowed)
				(footprints allowed)
			)
			(placement
				(enabled no)
				(sheetname "")
			)
			(fill
				(thermal_gap 0.5)
				(thermal_bridge_width 0.5)
				(island_removal_mode 0)
			)
			(polygon
				(pts
					(xy 343.746328 -157.226) (xy 343.238328 -157.226) (xy 343.238328 -156.845) (xy 343.746328 -156.845)
				)
			)
		)
		(zone
			(layer "F.Cu")
			(hatch none 0.5)
			(connect_pads
				(clearance 0)
			)
			(min_thickness 0.25)
			(keepout
				(tracks allowed)
				(vias not_allowed)
				(pads allowed)
				(copperpour not_allowed)
				(footprints allowed)
			)
			(placement
				(enabled no)
				(sheetname "")
			)
			(fill
				(thermal_gap 0.5)
				(thermal_bridge_width 0.5)
				(island_removal_mode 0)
			)
			(polygon
				(pts
					(xy 343.746328 -156.845) (xy 343.238328 -156.845) (xy 343.238328 -157.226) (xy 343.746328 -157.226)
				)
			)
		)
	)
	(footprint ""
		(layer "F.Cu")
		(at 193.5099 -70.88124)
		(property "Reference" "R4D72"
			(at 0 0 0)
			(layer "F.SilkS")
			(hide yes)
			(effects
				(font
					(size 1.27 1.27)
				)
			)
		)
		(property "Value" ""
			(at 0 0 0)
			(layer "F.Fab")
			(effects
				(font
					(size 1.27 1.27)
				)
			)
		)
		(duplicate_pad_numbers_are_jumpers no)
		(fp_poly
			(pts
				(xy -0.2794 -0.1016) (xy 0.2794 -0.1016) (xy 0.2794 0.9906) (xy -0.2794 0.9906)
			)
			(stroke
				(width 0)
				(type default)
			)
			(fill no)
			(layer "F.CrtYd")
		)
		(fp_line
			(start -0.2794 -0.1016)
			(end -0.2794 0.9906)
			(stroke
				(width 0.1)
				(type default)
			)
			(layer "F.Fab")
		)
		(fp_line
			(start -0.2794 0.9906)
			(end 0.2794 0.9906)
			(stroke
				(width 0.1)
				(type default)
			)
			(layer "F.Fab")
		)
		(fp_line
			(start 0.2794 -0.1016)
			(end -0.2794 -0.1016)
			(stroke
				(width 0.1)
				(type default)
			)
			(layer "F.Fab")
		)
		(fp_line
			(start 0.2794 0.9906)
			(end 0.2794 -0.1016)
			(stroke
				(width 0.1)
				(type default)
			)
			(layer "F.Fab")
		)
		(pad "1" smd rect
			(at 0 0)
			(size 0.508 0.508)
			(layers "F.Cu" "F.Mask" "F.Paste")
			(net "VR_PVCCIN_CPU0_PH3_OCSET")
		)
		(pad "2" smd rect
			(at 0 0.889)
			(size 0.508 0.508)
			(layers "F.Cu" "F.Mask" "F.Paste")
			(net "GND")
		)
		(zone
			(layer "F.Cu")
			(hatch none 0.5)
			(connect_pads
				(clearance 0)
			)
			(min_thickness 0.25)
			(keepout
				(tracks allowed)
				(vias not_allowed)
				(pads allowed)
				(copperpour not_allowed)
				(footprints allowed)
			)
			(placement
				(enabled no)
				(sheetname "")
			)
			(fill
				(thermal_gap 0.5)
				(thermal_bridge_width 0.5)
				(island_removal_mode 0)
			)
			(polygon
				(pts
					(xy 193.2559 -70.62724) (xy 193.7639 -70.62724) (xy 193.7639 -70.24624) (xy 193.2559 -70.24624)
				)
			)
		)
		(zone
			(layer "F.Cu")
			(hatch none 0.5)
			(connect_pads
				(clearance 0)
			)
			(min_thickness 0.25)
			(keepout
				(tracks not_allowed)
				(vias allowed)
				(pads allowed)
				(copperpour not_allowed)
				(footprints allowed)
			)
			(placement
				(enabled no)
				(sheetname "")
			)
			(fill
				(thermal_gap 0.5)
				(thermal_bridge_width 0.5)
				(island_removal_mode 0)
			)
			(polygon
				(pts
					(xy 193.2559 -70.24624) (xy 193.7639 -70.24624) (xy 193.7639 -70.62724) (xy 193.2559 -70.62724)
				)
			)
		)
	)
	(footprint ""
		(layer "F.Cu")
		(at 353.810062 -128.493266 180)
		(property "Reference" "R7B12"
			(at 0 0 180)
			(layer "F.SilkS")
			(hide yes)
			(effects
				(font
					(size 1.27 1.27)
				)
			)
		)
		(property "Value" ""
			(at 0 0 180)
			(layer "F.Fab")
			(effects
				(font
					(size 1.27 1.27)
				)
			)
		)
		(duplicate_pad_numbers_are_jumpers no)
		(fp_poly
			(pts
				(xy -0.2794 -0.1016) (xy 0.2794 -0.1016) (xy 0.2794 0.9906) (xy -0.2794 0.9906)
			)
			(stroke
				(width 0)
				(type default)
			)
			(fill no)
			(layer "F.CrtYd")
		)
		(fp_line
			(start 0.2794 0.9906)
			(end 0.2794 -0.1016)
			(stroke
				(width 0.1)
				(type default)
			)
			(layer "F.Fab")
		)
		(fp_line
			(start 0.2794 -0.1016)
			(end -0.2794 -0.1016)
			(stroke
				(width 0.1)
				(type default)
			)
			(layer "F.Fab")
		)
		(fp_line
			(start -0.2794 0.9906)
			(end 0.2794 0.9906)
			(stroke
				(width 0.1)
				(type default)
			)
			(layer "F.Fab")
		)
		(fp_line
			(start -0.2794 -0.1016)
			(end -0.2794 0.9906)
			(stroke
				(width 0.1)
				(type default)
			)
			(layer "F.Fab")
		)
		(pad "1" smd rect
			(at 0 0 180)
			(size 0.508 0.508)
			(layers "F.Cu" "F.Mask" "F.Paste")
			(net "PWRGD_PVPP_DEF_R")
		)
		(pad "2" smd rect
			(at 0 0.889 180)
			(size 0.508 0.508)
			(layers "F.Cu" "F.Mask" "F.Paste")
			(net "PWRGD_PVPP_DEF")
		)
		(zone
			(layer "F.Cu")
			(hatch none 0.5)
			(connect_pads
				(clearance 0)
			)
			(min_thickness 0.25)
			(keepout
				(tracks not_allowed)
				(vias allowed)
				(pads allowed)
				(copperpour not_allowed)
				(footprints allowed)
			)
			(placement
				(enabled no)
				(sheetname "")
			)
			(fill
				(thermal_gap 0.5)
				(thermal_bridge_width 0.5)
				(island_removal_mode 0)
			)
			(polygon
				(pts
					(xy 354.064062 -129.128266) (xy 353.556062 -129.128266) (xy 353.556062 -128.747266) (xy 354.064062 -128.747266)
				)
			)
		)
		(zone
			(layer "F.Cu")
			(hatch none 0.5)
			(connect_pads
				(clearance 0)
			)
			(min_thickness 0.25)
			(keepout
				(tracks allowed)
				(vias not_allowed)
				(pads allowed)
				(copperpour not_allowed)
				(footprints allowed)
			)
			(placement
				(enabled no)
				(sheetname "")
			)
			(fill
				(thermal_gap 0.5)
				(thermal_bridge_width 0.5)
				(island_removal_mode 0)
			)
			(polygon
				(pts
					(xy 354.064062 -128.747266) (xy 353.556062 -128.747266) (xy 353.556062 -129.128266) (xy 354.064062 -129.128266)
				)
			)
		)
	)
	(footprint ""
		(layer "F.Cu")
		(at 183.215026 -125.6157 180)
		(property "Reference" "R12W8"
			(at 0 0 180)
			(layer "F.SilkS")
			(hide yes)
			(effects
				(font
					(size 1.27 1.27)
				)
			)
		)
		(property "Value" "*"
			(at 0.064008 -4.108196 180)
			(unlocked yes)
			(layer "F.Fab")
			(hide yes)
			(effects
				(font
					(size 1.27 1.016)
					(thickness 0.1524)
				)
			)
		)
		(property "Device Type" "4D02R2F-GP_SMD-RG2-4D02R2F-GP,A"
			(at 0.064008 -5.632196 180)
			(unlocked yes)
			(layer "F.Fab")
			(hide yes)
			(effects
				(font
					(size 1.27 1.016)
					(thickness 0.1524)
				)
			)
		)
		(duplicate_pad_numbers_are_jumpers no)
		(fp_line
			(start 0.508 -0.9398)
			(end -0.508 -0.9398)
			(stroke
				(width 0.1524)
				(type default)
			)
			(layer "F.SilkS")
		)
		(fp_line
			(start -0.508 -0.9398)
			(end -0.508 0.9398)
			(stroke
				(width 0.1524)
				(type default)
			)
			(layer "F.SilkS")
		)
		(fp_rect
			(start -0.508 0.9398)
			(end 0.508 -0.9398)
			(stroke
				(width 0)
				(type default)
			)
			(fill no)
			(layer "F.CrtYd")
		)
		(fp_rect
			(start -0.508 0.9398)
			(end 0.508 -0.9398)
			(stroke
				(width 0)
				(type default)
			)
			(fill no)
			(layer "F.Fab")
		)
		(pad "1" smd custom
			(at 0 -0.4445 180)
			(size 0.1397 0.1397)
			(layers "F.Cu" "F.Mask" "F.Paste")
			(net "P12V_STBY")
			(options
				(clearance outline)
				(anchor circle)
			)
			(primitives
				(gr_poly
					(pts
						(arc
							(start -0.1778 -0.2794)
							(mid -0.249642 -0.249642)
							(end -0.2794 -0.1778)
						)
						(arc
							(start -0.2794 0.1778)
							(mid -0.249642 0.249642)
							(end -0.1778 0.2794)
						)
						(arc
							(start 0.1778 0.2794)
							(mid 0.249642 0.249642)
							(end 0.2794 0.1778)
						)
						(arc
							(start 0.2794 -0.1778)
							(mid 0.249642 -0.249642)
							(end 0.1778 -0.2794)
						)
					)
					(width 0)
					(fill yes)
				)
			)
		)
		(pad "2" smd custom
			(at 0 0.4445 180)
			(size 0.1397 0.1397)
			(layers "F.Cu" "F.Mask" "F.Paste")
			(net "P12V_NVDIMM_DEF_D")
			(options
				(clearance outline)
				(anchor circle)
			)
			(primitives
				(gr_poly
					(pts
						(arc
							(start -0.1778 -0.2794)
							(mid -0.249642 -0.249642)
							(end -0.2794 -0.1778)
						)
						(arc
							(start -0.2794 0.1778)
							(mid -0.249642 0.249642)
							(end -0.1778 0.2794)
						)
						(arc
							(start 0.1778 0.2794)
							(mid 0.249642 0.249642)
							(end 0.2794 0.1778)
						)
						(arc
							(start 0.2794 -0.1778)
							(mid 0.249642 -0.249642)
							(end 0.1778 -0.2794)
						)
					)
					(width 0)
					(fill yes)
				)
			)
		)
	)
	(footprint ""
		(layer "F.Cu")
		(at 467.0806 -126.6952 180)
		(property "Reference" "R9B14"
			(at 0 0 180)
			(layer "F.SilkS")
			(hide yes)
			(effects
				(font
					(size 1.27 1.27)
				)
			)
		)
		(property "Value" ""
			(at 0 0 180)
			(layer "F.Fab")
			(effects
				(font
					(size 1.27 1.27)
				)
			)
		)
		(duplicate_pad_numbers_are_jumpers no)
		(fp_poly
			(pts
				(xy -0.2794 -0.1016) (xy 0.2794 -0.1016) (xy 0.2794 0.9906) (xy -0.2794 0.9906)
			)
			(stroke
				(width 0)
				(type default)
			)
			(fill no)
			(layer "F.CrtYd")
		)
		(fp_line
			(start 0.2794 0.9906)
			(end 0.2794 -0.1016)
			(stroke
				(width 0.1)
				(type default)
			)
			(layer "F.Fab")
		)
		(fp_line
			(start 0.2794 -0.1016)
			(end -0.2794 -0.1016)
			(stroke
				(width 0.1)
				(type default)
			)
			(layer "F.Fab")
		)
		(fp_line
			(start -0.2794 0.9906)
			(end 0.2794 0.9906)
			(stroke
				(width 0.1)
				(type default)
			)
			(layer "F.Fab")
		)
		(fp_line
			(start -0.2794 -0.1016)
			(end -0.2794 0.9906)
			(stroke
				(width 0.1)
				(type default)
			)
			(layer "F.Fab")
		)
		(pad "1" smd rect
			(at 0 0 180)
			(size 0.508 0.508)
			(layers "F.Cu" "F.Mask" "F.Paste")
			(net "PWRGD_CPU0_G")
		)
		(pad "2" smd rect
			(at 0 0.889 180)
			(size 0.508 0.508)
			(layers "F.Cu" "F.Mask" "F.Paste")
			(net "PWRGD_CPU0_G_R")
		)
		(zone
			(layer "F.Cu")
			(hatch none 0.5)
			(connect_pads
				(clearance 0)
			)
			(min_thickness 0.25)
			(keepout
				(tracks not_allowed)
				(vias allowed)
				(pads allowed)
				(copperpour not_allowed)
				(footprints allowed)
			)
			(placement
				(enabled no)
				(sheetname "")
			)
			(fill
				(thermal_gap 0.5)
				(thermal_bridge_width 0.5)
				(island_removal_mode 0)
			)
			(polygon
				(pts
					(xy 467.3346 -127.3302) (xy 466.8266 -127.3302) (xy 466.8266 -126.9492) (xy 467.3346 -126.9492)
				)
			)
		)
		(zone
			(layer "F.Cu")
			(hatch none 0.5)
			(connect_pads
				(clearance 0)
			)
			(min_thickness 0.25)
			(keepout
				(tracks allowed)
				(vias not_allowed)
				(pads allowed)
				(copperpour not_allowed)
				(footprints allowed)
			)
			(placement
				(enabled no)
				(sheetname "")
			)
			(fill
				(thermal_gap 0.5)
				(thermal_bridge_width 0.5)
				(island_removal_mode 0)
			)
			(polygon
				(pts
					(xy 467.3346 -126.9492) (xy 466.8266 -126.9492) (xy 466.8266 -127.3302) (xy 467.3346 -127.3302)
				)
			)
		)
	)
	(footprint ""
		(layer "F.Cu")
		(at 28.85948 -96.19234 -90)
		(property "Reference" "R1C37"
			(at 0 0 270)
			(layer "F.SilkS")
			(hide yes)
			(effects
				(font
					(size 1.27 1.27)
				)
			)
		)
		(property "Value" ""
			(at 0 0 270)
			(layer "F.Fab")
			(effects
				(font
					(size 1.27 1.27)
				)
			)
		)
		(duplicate_pad_numbers_are_jumpers no)
		(fp_poly
			(pts
				(xy -0.2794 -0.1016) (xy 0.2794 -0.1016) (xy 0.2794 0.9906) (xy -0.2794 0.9906)
			)
			(stroke
				(width 0)
				(type default)
			)
			(fill no)
			(layer "F.CrtYd")
		)
		(fp_line
			(start -0.2794 0.9906)
			(end 0.2794 0.9906)
			(stroke
				(width 0.1)
				(type default)
			)
			(layer "F.Fab")
		)
		(fp_line
			(start 0.2794 0.9906)
			(end 0.2794 -0.1016)
			(stroke
				(width 0.1)
				(type default)
			)
			(layer "F.Fab")
		)
		(fp_line
			(start -0.2794 -0.1016)
			(end -0.2794 0.9906)
			(stroke
				(width 0.1)
				(type default)
			)
			(layer "F.Fab")
		)
		(fp_line
			(start 0.2794 -0.1016)
			(end -0.2794 -0.1016)
			(stroke
				(width 0.1)
				(type default)
			)
			(layer "F.Fab")
		)
		(pad "1" smd rect
			(at 0 0 270)
			(size 0.508 0.508)
			(layers "F.Cu" "F.Mask" "F.Paste")
			(net "VR_PVSA_CPU1_OCSET")
		)
		(pad "2" smd rect
			(at 0 0.889 270)
			(size 0.508 0.508)
			(layers "F.Cu" "F.Mask" "F.Paste")
			(net "GND")
		)
		(zone
			(layer "F.Cu")
			(hatch none 0.5)
			(connect_pads
				(clearance 0)
			)
			(min_thickness 0.25)
			(keepout
				(tracks not_allowed)
				(vias allowed)
				(pads allowed)
				(copperpour not_allowed)
				(footprints allowed)
			)
			(placement
				(enabled no)
				(sheetname "")
			)
			(fill
				(thermal_gap 0.5)
				(thermal_bridge_width 0.5)
				(island_removal_mode 0)
			)
			(polygon
				(pts
					(xy 28.22448 -96.44634) (xy 28.22448 -95.93834) (xy 28.60548 -95.93834) (xy 28.60548 -96.44634)
				)
			)
		)
		(zone
			(layer "F.Cu")
			(hatch none 0.5)
			(connect_pads
				(clearance 0)
			)
			(min_thickness 0.25)
			(keepout
				(tracks allowed)
				(vias not_allowed)
				(pads allowed)
				(copperpour not_allowed)
				(footprints allowed)
			)
			(placement
				(enabled no)
				(sheetname "")
			)
			(fill
				(thermal_gap 0.5)
				(thermal_bridge_width 0.5)
				(island_removal_mode 0)
			)
			(polygon
				(pts
					(xy 28.60548 -96.44634) (xy 28.60548 -95.93834) (xy 28.22448 -95.93834) (xy 28.22448 -96.44634)
				)
			)
		)
	)
	(footprint ""
		(layer "F.Cu")
		(at 107.240578 -84.890102)
		(property "Reference" "C3D1"
			(at 0 0 0)
			(layer "F.SilkS")
			(hide yes)
			(effects
				(font
					(size 1.27 1.27)
				)
			)
		)
		(property "Value" ""
			(at 0 0 0)
			(layer "F.Fab")
			(effects
				(font
					(size 1.27 1.27)
				)
			)
		)
		(duplicate_pad_numbers_are_jumpers no)
		(fp_poly
			(pts
				(xy -0.4953 -0.2032) (xy 0.4953 -0.2032) (xy 0.4953 1.6002) (xy -0.4953 1.6002)
			)
			(stroke
				(width 0)
				(type default)
			)
			(fill no)
			(layer "F.CrtYd")
		)
		(fp_line
			(start -0.4953 -0.2032)
			(end 0.4953 -0.2032)
			(stroke
				(width 0.1)
				(type default)
			)
			(layer "F.Fab")
		)
		(fp_line
			(start -0.4953 1.6002)
			(end -0.4953 -0.2032)
			(stroke
				(width 0.1)
				(type default)
			)
			(layer "F.Fab")
		)
		(fp_line
			(start 0.4953 -0.2032)
			(end 0.4953 1.6002)
			(stroke
				(width 0.1)
				(type default)
			)
			(layer "F.Fab")
		)
		(fp_line
			(start 0.4953 1.6002)
			(end -0.4953 1.6002)
			(stroke
				(width 0.1)
				(type default)
			)
			(layer "F.Fab")
		)
		(pad "1" smd rect
			(at 0 0)
			(size 0.762 0.889)
			(layers "F.Cu" "F.Mask" "F.Paste")
			(net "PVDDQ_KLM")
		)
		(pad "2" smd rect
			(at 0 1.397)
			(size 0.762 0.889)
			(layers "F.Cu" "F.Mask" "F.Paste")
			(net "GND")
		)
		(zone
			(layer "F.Cu")
			(hatch none 0.5)
			(connect_pads
				(clearance 0)
			)
			(min_thickness 0.25)
			(keepout
				(tracks not_allowed)
				(vias allowed)
				(pads allowed)
				(copperpour not_allowed)
				(footprints allowed)
			)
			(placement
				(enabled no)
				(sheetname "")
			)
			(fill
				(thermal_gap 0.5)
				(thermal_bridge_width 0.5)
				(island_removal_mode 0)
			)
			(polygon
				(pts
					(xy 106.859578 -84.445602) (xy 107.621578 -84.445602) (xy 107.621578 -83.937602) (xy 106.859578 -83.937602)
				)
			)
		)
	)
)
